# SCM (Grand Teton) — schematic netlist excerpt (pin names and nets, part order shuffled) for the footprints in the layout excerpt that follows; sources: Cadence DE-HDL packaged netlist, KiCad conversion of 12092022_DA0F0TMDCD0_F0T_Management_Board_D_brd_V3_OCP.brd

R737  Q_RES  4.7K 1% EMPTY  pkg 0402LF  page 30 : A = P3V3_AUX ; B = SPA_SIN_SW_BUF
R616  Q_RES  0 5% CHIP  pkg 0402LF  page 48 : A = FM_JTAG_TCK_MUX_BMC_SEL_R ; B = FM_JTAG_TCK_MUX_BMC_SEL

(kicad_pcb
	(version 20260206)
	(generator "pcbnew")
	(generator_version "10.0")
	(general
		(thickness 1.6)
		(legacy_teardrops no)
	)
	(paper "A4")
	(title_block
		(title "12092022_DA0F0TMDCD0_F0T_Management_Board_D_brd_V3_OCP.brd")
		(comment 1 "Grand Teton / footprints 471-472 of 1440")
	)
	(layers
		(0 "F.Cu" signal "TOP")
		(4 "In1.Cu" signal "GND")
		(6 "In2.Cu" signal "IN1")
		(8 "In3.Cu" signal "GND1")
		(10 "In4.Cu" signal "IN2")
		(12 "In5.Cu" signal "VCC")
		(14 "In6.Cu" signal "VCC1")
		(16 "In7.Cu" signal "IN3")
		(18 "In8.Cu" signal "GND2")
		(20 "In9.Cu" signal "IN4")
		(22 "In10.Cu" signal "GND3")
		(2 "B.Cu" signal "BOTTOM")
		(9 "F.Adhes" user "F.Adhesive")
		(11 "B.Adhes" user "B.Adhesive")
		(13 "F.Paste" user "Package Geometry/Pastemask Top")
		(15 "B.Paste" user "Package Geometry/Pastemask Bottom")
		(5 "F.SilkS" user "Ref Des/Silkscreen Top")
		(7 "B.SilkS" user "Ref Des/Silkscreen Bottom")
		(1 "F.Mask" user "Board Geometry/Soldermask Top")
		(3 "B.Mask" user "Board Geometry/Soldermask Bottom")
		(17 "Dwgs.User" user "User.Drawings")
		(19 "Cmts.User" user "User.Comments")
		(21 "Eco1.User" user "User.Eco1")
		(23 "Eco2.User" user "User.Eco2")
		(25 "Edge.Cuts" user "Board Geometry/Outline")
		(27 "Margin" user)
		(31 "F.CrtYd" user "Package Geometry/Place Bound Top")
		(29 "B.CrtYd" user "Package Geometry/Place Bound Bottom")
		(35 "F.Fab" user "Ref Des/Assembly Top")
		(33 "B.Fab" user "Ref Des/Assembly Bottom")
	)
	(footprint ""
		(layer "F.Cu")
		(at 19.812 -65.8368)
		(property "Reference" "R737"
			(at 0 0 0)
			(layer "F.SilkS")
			(hide yes)
			(effects
				(font
					(size 1.27 1.27)
				)
			)
		)
		(property "Value" ""
			(at 0 0 0)
			(layer "F.Fab")
			(effects
				(font
					(size 1.27 1.27)
				)
			)
		)
		(duplicate_pad_numbers_are_jumpers no)
		(fp_line
			(start -0.7874 -0.4064)
			(end 0.7874 -0.4064)
			(stroke
				(width 0.1524)
				(type default)
			)
			(layer "F.SilkS")
		)
		(fp_line
			(start -0.7874 0.4064)
			(end -0.7874 -0.4064)
			(stroke
				(width 0.1524)
				(type default)
			)
			(layer "F.SilkS")
		)
		(fp_line
			(start 0.7874 -0.4064)
			(end 0.7874 0.4064)
			(stroke
				(width 0.1524)
				(type default)
			)
			(layer "F.SilkS")
		)
		(fp_line
			(start 0.7874 0.4064)
			(end -0.7874 0.4064)
			(stroke
				(width 0.1524)
				(type default)
			)
			(layer "F.SilkS")
		)
		(fp_line
			(start -0.67945 -0.305054)
			(end -0.12065 -0.305054)
			(stroke
				(width 0.1)
				(type default)
			)
			(layer "F.Fab")
		)
		(fp_line
			(start -0.67945 0.3048)
			(end -0.67945 -0.305054)
			(stroke
				(width 0.1)
				(type default)
			)
			(layer "F.Fab")
		)
		(fp_line
			(start -0.12065 -0.305054)
			(end -0.12065 -0.2794)
			(stroke
				(width 0.1)
				(type default)
			)
			(layer "F.Fab")
		)
		(fp_line
			(start -0.12065 -0.2794)
			(end 0.12065 -0.2794)
			(stroke
				(width 0.1)
				(type default)
			)
			(layer "F.Fab")
		)
		(fp_line
			(start -0.12065 0.2794)
			(end -0.12065 0.3048)
			(stroke
				(width 0.1)
				(type default)
			)
			(layer "F.Fab")
		)
		(fp_line
			(start -0.12065 0.3048)
			(end -0.67945 0.3048)
			(stroke
				(width 0.1)
				(type default)
			)
			(layer "F.Fab")
		)
		(fp_line
			(start 0.120396 0.2794)
			(end -0.12065 0.2794)
			(stroke
				(width 0.1)
				(type default)
			)
			(layer "F.Fab")
		)
		(fp_line
			(start 0.120396 0.3048)
			(end 0.120396 0.2794)
			(stroke
				(width 0.1)
				(type default)
			)
			(layer "F.Fab")
		)
		(fp_line
			(start 0.12065 -0.3048)
			(end 0.67945 -0.3048)
			(stroke
				(width 0.1)
				(type default)
			)
			(layer "F.Fab")
		)
		(fp_line
			(start 0.12065 -0.2794)
			(end 0.12065 -0.3048)
			(stroke
				(width 0.1)
				(type default)
			)
			(layer "F.Fab")
		)
		(fp_line
			(start 0.67945 -0.3048)
			(end 0.67945 0.3048)
			(stroke
				(width 0.1)
				(type default)
			)
			(layer "F.Fab")
		)
		(fp_line
			(start 0.67945 0.3048)
			(end 0.120396 0.3048)
			(stroke
				(width 0.1)
				(type default)
			)
			(layer "F.Fab")
		)
		(pad "1" smd circle
			(at -0.40005 0)
			(size 0 0)
			(layers "F.Cu" "F.Mask" "F.Paste")
			(net "P3V3_AUX")
		)
		(pad "2" smd circle
			(at 0.40005 0)
			(size 0 0)
			(layers "F.Cu" "F.Mask" "F.Paste")
			(net "SPA_SIN_SW_BUF")
		)
	)
	(footprint ""
		(layer "F.Cu")
		(at 78.000098 -74.476356 90)
		(property "Reference" "R616"
			(at 0 0 90)
			(layer "F.SilkS")
			(hide yes)
			(effects
				(font
					(size 1.27 1.27)
				)
			)
		)
		(property "Value" ""
			(at 0 0 90)
			(layer "F.Fab")
			(effects
				(font
					(size 1.27 1.27)
				)
			)
		)
		(duplicate_pad_numbers_are_jumpers no)
		(fp_line
			(start 0.7874 -0.4064)
			(end 0.7874 0.4064)
			(stroke
				(width 0.1524)
				(type default)
			)
			(layer "F.SilkS")
		)
		(fp_line
			(start -0.7874 -0.4064)
			(end 0.7874 -0.4064)
			(stroke
				(width 0.1524)
				(type default)
			)
			(layer "F.SilkS")
		)
		(fp_line
			(start 0.7874 0.4064)
			(end -0.7874 0.4064)
			(stroke
				(width 0.1524)
				(type default)
			)
			(layer "F.SilkS")
		)
		(fp_line
			(start -0.7874 0.4064)
			(end -0.7874 -0.4064)
			(stroke
				(width 0.1524)
				(type default)
			)
			(layer "F.SilkS")
		)
		(fp_line
			(start -0.12065 -0.305054)
			(end -0.12065 -0.2794)
			(stroke
				(width 0.1)
				(type default)
			)
			(layer "F.Fab")
		)
		(fp_line
			(start -0.67945 -0.305054)
			(end -0.12065 -0.305054)
			(stroke
				(width 0.1)
				(type default)
			)
			(layer "F.Fab")
		)
		(fp_line
			(start 0.67945 -0.3048)
			(end 0.67945 0.3048)
			(stroke
				(width 0.1)
				(type default)
			)
			(layer "F.Fab")
		)
		(fp_line
			(start 0.12065 -0.3048)
			(end 0.67945 -0.3048)
			(stroke
				(width 0.1)
				(type default)
			)
			(layer "F.Fab")
		)
		(fp_line
			(start 0.12065 -0.2794)
			(end 0.12065 -0.3048)
			(stroke
				(width 0.1)
				(type default)
			)
			(layer "F.Fab")
		)
		(fp_line
			(start -0.12065 -0.2794)
			(end 0.12065 -0.2794)
			(stroke
				(width 0.1)
				(type default)
			)
			(layer "F.Fab")
		)
		(fp_line
			(start 0.120396 0.2794)
			(end -0.12065 0.2794)
			(stroke
				(width 0.1)
				(type default)
			)
			(layer "F.Fab")
		)
		(fp_line
			(start -0.12065 0.2794)
			(end -0.12065 0.3048)
			(stroke
				(width 0.1)
				(type default)
			)
			(layer "F.Fab")
		)
		(fp_line
			(start 0.67945 0.3048)
			(end 0.120396 0.3048)
			(stroke
				(width 0.1)
				(type default)
			)
			(layer "F.Fab")
		)
		(fp_line
			(start 0.120396 0.3048)
			(end 0.120396 0.2794)
			(stroke
				(width 0.1)
				(type default)
			)
			(layer "F.Fab")
		)
		(fp_line
			(start -0.12065 0.3048)
			(end -0.67945 0.3048)
			(stroke
				(width 0.1)
				(type default)
			)
			(layer "F.Fab")
		)
		(fp_line
			(start -0.67945 0.3048)
			(end -0.67945 -0.305054)
			(stroke
				(width 0.1)
				(type default)
			)
			(layer "F.Fab")
		)
		(pad "1" smd circle
			(at -0.40005 0 90)
			(size 0 0)
			(layers "F.Cu" "F.Mask" "F.Paste")
			(net "FM_JTAG_TCK_MUX_BMC_SEL_R")
		)
		(pad "2" smd circle
			(at 0.40005 0 90)
			(size 0 0)
			(layers "F.Cu" "F.Mask" "F.Paste")
			(net "FM_JTAG_TCK_MUX_BMC_SEL")
		)
	)
)
